(kicad_pcb
	(version 20260206)
	(generator "pcbnew")
	(generator_version "10.0")
	(general
		(thickness 1.6)
		(legacy_teardrops no)
	)
	(paper "A4")
	(title_block
		(title "03242023_DA0F0TMBIJ0_F0T_Motherboard_J_brd_V01_OCP.brd")
		(comment 1 "Grand Teton / footprints 5193-5198 of 6105")
	)
	(layers
		(0 "F.Cu" signal "TOP")
		(4 "In1.Cu" signal "GND")
		(6 "In2.Cu" signal "IN1")
		(8 "In3.Cu" signal "GND1")
		(10 "In4.Cu" signal "IN2")
		(12 "In5.Cu" signal "GND2")
		(14 "In6.Cu" signal "IN3")
		(16 "In7.Cu" signal "GND3")
		(18 "In8.Cu" signal "VCC")
		(20 "In9.Cu" signal "VCC1")
		(22 "In10.Cu" signal "GND4")
		(24 "In11.Cu" signal "IN4")
		(26 "In12.Cu" signal "GND5")
		(28 "In13.Cu" signal "IN5")
		(30 "In14.Cu" signal "GND6")
		(32 "In15.Cu" signal "IN6")
		(34 "In16.Cu" signal "GND7")
		(2 "B.Cu" signal "BOTTOM")
		(9 "F.Adhes" user "F.Adhesive")
		(11 "B.Adhes" user "B.Adhesive")
		(13 "F.Paste" user "Package Geometry/Pastemask Top")
		(15 "B.Paste" user "Package Geometry/Pastemask Bottom")
		(5 "F.SilkS" user "Ref Des/Silkscreen Top")
		(7 "B.SilkS" user "Ref Des/Silkscreen Bottom")
		(1 "F.Mask" user "Board Geometry/Soldermask Top")
		(3 "B.Mask" user "Board Geometry/Soldermask Bottom")
		(17 "Dwgs.User" user "User.Drawings")
		(19 "Cmts.User" user "User.Comments")
		(21 "Eco1.User" user "User.Eco1")
		(23 "Eco2.User" user "User.Eco2")
		(25 "Edge.Cuts" user "Board Geometry/Outline")
		(27 "Margin" user)
		(31 "F.CrtYd" user "Package Geometry/Place Bound Top")
		(29 "B.CrtYd" user "Package Geometry/Place Bound Bottom")
		(35 "F.Fab" user "Ref Des/Assembly Top")
		(33 "B.Fab" user "Ref Des/Assembly Bottom")
	)
	(footprint ""
		(layer "B.Cu")
		(at 99.53752 -422.145968 90)
		(property "Reference" "R4556"
			(at 0 0 90)
			(layer "B.SilkS")
			(hide yes)
			(effects
				(font
					(size 1.27 1.27)
				)
				(justify mirror)
			)
		)
		(property "Value" ""
			(at 0 0 90)
			(layer "B.Fab")
			(effects
				(font
					(size 1.27 1.27)
				)
				(justify mirror)
			)
		)
		(duplicate_pad_numbers_are_jumpers no)
		(fp_line
			(start 0.7874 -0.4064)
			(end -0.7874 -0.4064)
			(stroke
				(width 0.1524)
				(type default)
			)
			(layer "B.SilkS")
		)
		(fp_line
			(start -0.7874 -0.4064)
			(end -0.7874 0.4064)
			(stroke
				(width 0.1524)
				(type default)
			)
			(layer "B.SilkS")
		)
		(fp_line
			(start 0.7874 0.4064)
			(end 0.7874 -0.4064)
			(stroke
				(width 0.1524)
				(type default)
			)
			(layer "B.SilkS")
		)
		(fp_line
			(start -0.7874 0.4064)
			(end 0.7874 0.4064)
			(stroke
				(width 0.1524)
				(type default)
			)
			(layer "B.SilkS")
		)
		(fp_line
			(start 0.67945 -0.305054)
			(end 0.12065 -0.305054)
			(stroke
				(width 0.1)
				(type default)
			)
			(layer "B.Fab")
		)
		(fp_line
			(start 0.12065 -0.305054)
			(end 0.12065 -0.2794)
			(stroke
				(width 0.1)
				(type default)
			)
			(layer "B.Fab")
		)
		(fp_line
			(start -0.12065 -0.3048)
			(end -0.67945 -0.3048)
			(stroke
				(width 0.1)
				(type default)
			)
			(layer "B.Fab")
		)
		(fp_line
			(start -0.67945 -0.3048)
			(end -0.67945 0.3048)
			(stroke
				(width 0.1)
				(type default)
			)
			(layer "B.Fab")
		)
		(fp_line
			(start 0.12065 -0.2794)
			(end -0.12065 -0.2794)
			(stroke
				(width 0.1)
				(type default)
			)
			(layer "B.Fab")
		)
		(fp_line
			(start -0.12065 -0.2794)
			(end -0.12065 -0.3048)
			(stroke
				(width 0.1)
				(type default)
			)
			(layer "B.Fab")
		)
		(fp_line
			(start 0.12065 0.2794)
			(end 0.12065 0.3048)
			(stroke
				(width 0.1)
				(type default)
			)
			(layer "B.Fab")
		)
		(fp_line
			(start -0.120396 0.2794)
			(end 0.12065 0.2794)
			(stroke
				(width 0.1)
				(type default)
			)
			(layer "B.Fab")
		)
		(fp_line
			(start 0.67945 0.3048)
			(end 0.67945 -0.305054)
			(stroke
				(width 0.1)
				(type default)
			)
			(layer "B.Fab")
		)
		(fp_line
			(start 0.12065 0.3048)
			(end 0.67945 0.3048)
			(stroke
				(width 0.1)
				(type default)
			)
			(layer "B.Fab")
		)
		(fp_line
			(start -0.120396 0.3048)
			(end -0.120396 0.2794)
			(stroke
				(width 0.1)
				(type default)
			)
			(layer "B.Fab")
		)
		(fp_line
			(start -0.67945 0.3048)
			(end -0.120396 0.3048)
			(stroke
				(width 0.1)
				(type default)
			)
			(layer "B.Fab")
		)
		(pad "1" smd circle
			(at 0.40005 0 270)
			(size 0 0)
			(layers "B.Cu" "B.Mask" "B.Paste")
			(net "HGX_DETECT_N_R")
		)
		(pad "2" smd circle
			(at -0.40005 0 270)
			(size 0 0)
			(layers "B.Cu" "B.Mask" "B.Paste")
			(net "HGX_DETECT_N")
		)
	)
	(footprint ""
		(layer "B.Cu")
		(at 237.230666 -422.993058 90)
		(property "Reference" "R2906"
			(at 0 0 90)
			(layer "B.SilkS")
			(hide yes)
			(effects
				(font
					(size 1.27 1.27)
				)
				(justify mirror)
			)
		)
		(property "Value" ""
			(at 0 0 90)
			(layer "B.Fab")
			(effects
				(font
					(size 1.27 1.27)
				)
				(justify mirror)
			)
		)
		(duplicate_pad_numbers_are_jumpers no)
		(fp_line
			(start 0.7874 -0.4064)
			(end -0.7874 -0.4064)
			(stroke
				(width 0.1524)
				(type default)
			)
			(layer "B.SilkS")
		)
		(fp_line
			(start -0.7874 -0.4064)
			(end -0.7874 0.4064)
			(stroke
				(width 0.1524)
				(type default)
			)
			(layer "B.SilkS")
		)
		(fp_line
			(start 0.7874 0.4064)
			(end 0.7874 -0.4064)
			(stroke
				(width 0.1524)
				(type default)
			)
			(layer "B.SilkS")
		)
		(fp_line
			(start -0.7874 0.4064)
			(end 0.7874 0.4064)
			(stroke
				(width 0.1524)
				(type default)
			)
			(layer "B.SilkS")
		)
		(fp_line
			(start 0.67945 -0.305054)
			(end 0.12065 -0.305054)
			(stroke
				(width 0.1)
				(type default)
			)
			(layer "B.Fab")
		)
		(fp_line
			(start 0.12065 -0.305054)
			(end 0.12065 -0.2794)
			(stroke
				(width 0.1)
				(type default)
			)
			(layer "B.Fab")
		)
		(fp_line
			(start -0.12065 -0.3048)
			(end -0.67945 -0.3048)
			(stroke
				(width 0.1)
				(type default)
			)
			(layer "B.Fab")
		)
		(fp_line
			(start -0.67945 -0.3048)
			(end -0.67945 0.3048)
			(stroke
				(width 0.1)
				(type default)
			)
			(layer "B.Fab")
		)
		(fp_line
			(start 0.12065 -0.2794)
			(end -0.12065 -0.2794)
			(stroke
				(width 0.1)
				(type default)
			)
			(layer "B.Fab")
		)
		(fp_line
			(start -0.12065 -0.2794)
			(end -0.12065 -0.3048)
			(stroke
				(width 0.1)
				(type default)
			)
			(layer "B.Fab")
		)
		(fp_line
			(start 0.12065 0.2794)
			(end 0.12065 0.3048)
			(stroke
				(width 0.1)
				(type default)
			)
			(layer "B.Fab")
		)
		(fp_line
			(start -0.120396 0.2794)
			(end 0.12065 0.2794)
			(stroke
				(width 0.1)
				(type default)
			)
			(layer "B.Fab")
		)
		(fp_line
			(start 0.67945 0.3048)
			(end 0.67945 -0.305054)
			(stroke
				(width 0.1)
				(type default)
			)
			(layer "B.Fab")
		)
		(fp_line
			(start 0.12065 0.3048)
			(end 0.67945 0.3048)
			(stroke
				(width 0.1)
				(type default)
			)
			(layer "B.Fab")
		)
		(fp_line
			(start -0.120396 0.3048)
			(end -0.120396 0.2794)
			(stroke
				(width 0.1)
				(type default)
			)
			(layer "B.Fab")
		)
		(fp_line
			(start -0.67945 0.3048)
			(end -0.120396 0.3048)
			(stroke
				(width 0.1)
				(type default)
			)
			(layer "B.Fab")
		)
		(pad "1" smd circle
			(at 0.40005 0 270)
			(size 0 0)
			(layers "B.Cu" "B.Mask" "B.Paste")
			(net "FM_GPU_HSC_EN_BUF_R1")
		)
		(pad "2" smd circle
			(at -0.40005 0 270)
			(size 0 0)
			(layers "B.Cu" "B.Mask" "B.Paste")
			(net "FM_GPU_HSC_EN_BUF")
		)
	)
	(footprint ""
		(layer "B.Cu")
		(at 84.494624 -184.096152 90)
		(property "Reference" "R759"
			(at 0 0 90)
			(layer "B.SilkS")
			(hide yes)
			(effects
				(font
					(size 1.27 1.27)
				)
				(justify mirror)
			)
		)
		(property "Value" ""
			(at 0 0 90)
			(layer "B.Fab")
			(effects
				(font
					(size 1.27 1.27)
				)
				(justify mirror)
			)
		)
		(duplicate_pad_numbers_are_jumpers no)
		(fp_line
			(start 0.7874 -0.4064)
			(end -0.7874 -0.4064)
			(stroke
				(width 0.1524)
				(type default)
			)
			(layer "B.SilkS")
		)
		(fp_line
			(start -0.7874 -0.4064)
			(end -0.7874 0.4064)
			(stroke
				(width 0.1524)
				(type default)
			)
			(layer "B.SilkS")
		)
		(fp_line
			(start 0.7874 0.4064)
			(end 0.7874 -0.4064)
			(stroke
				(width 0.1524)
				(type default)
			)
			(layer "B.SilkS")
		)
		(fp_line
			(start -0.7874 0.4064)
			(end 0.7874 0.4064)
			(stroke
				(width 0.1524)
				(type default)
			)
			(layer "B.SilkS")
		)
		(fp_line
			(start 0.67945 -0.305054)
			(end 0.12065 -0.305054)
			(stroke
				(width 0.1)
				(type default)
			)
			(layer "B.Fab")
		)
		(fp_line
			(start 0.12065 -0.305054)
			(end 0.12065 -0.2794)
			(stroke
				(width 0.1)
				(type default)
			)
			(layer "B.Fab")
		)
		(fp_line
			(start -0.12065 -0.3048)
			(end -0.67945 -0.3048)
			(stroke
				(width 0.1)
				(type default)
			)
			(layer "B.Fab")
		)
		(fp_line
			(start -0.67945 -0.3048)
			(end -0.67945 0.3048)
			(stroke
				(width 0.1)
				(type default)
			)
			(layer "B.Fab")
		)
		(fp_line
			(start 0.12065 -0.2794)
			(end -0.12065 -0.2794)
			(stroke
				(width 0.1)
				(type default)
			)
			(layer "B.Fab")
		)
		(fp_line
			(start -0.12065 -0.2794)
			(end -0.12065 -0.3048)
			(stroke
				(width 0.1)
				(type default)
			)
			(layer "B.Fab")
		)
		(fp_line
			(start 0.12065 0.2794)
			(end 0.12065 0.3048)
			(stroke
				(width 0.1)
				(type default)
			)
			(layer "B.Fab")
		)
		(fp_line
			(start -0.120396 0.2794)
			(end 0.12065 0.2794)
			(stroke
				(width 0.1)
				(type default)
			)
			(layer "B.Fab")
		)
		(fp_line
			(start 0.67945 0.3048)
			(end 0.67945 -0.305054)
			(stroke
				(width 0.1)
				(type default)
			)
			(layer "B.Fab")
		)
		(fp_line
			(start 0.12065 0.3048)
			(end 0.67945 0.3048)
			(stroke
				(width 0.1)
				(type default)
			)
			(layer "B.Fab")
		)
		(fp_line
			(start -0.120396 0.3048)
			(end -0.120396 0.2794)
			(stroke
				(width 0.1)
				(type default)
			)
			(layer "B.Fab")
		)
		(fp_line
			(start -0.67945 0.3048)
			(end -0.120396 0.3048)
			(stroke
				(width 0.1)
				(type default)
			)
			(layer "B.Fab")
		)
		(pad "1" smd circle
			(at 0.40005 0 270)
			(size 0 0)
			(layers "B.Cu" "B.Mask" "B.Paste")
			(net "PVNN_TERM_CPU0")
		)
		(pad "2" smd circle
			(at -0.40005 0 270)
			(size 0 0)
			(layers "B.Cu" "B.Mask" "B.Paste")
			(net "H_CPU_PRDY_QS_GTL_N")
		)
	)
	(footprint ""
		(layer "B.Cu")
		(at 461.419448 -318.79159 90)
		(property "Reference" "R40"
			(at 0 0 90)
			(layer "B.SilkS")
			(hide yes)
			(effects
				(font
					(size 1.27 1.27)
				)
				(justify mirror)
			)
		)
		(property "Value" ""
			(at 0 0 90)
			(layer "B.Fab")
			(effects
				(font
					(size 1.27 1.27)
				)
				(justify mirror)
			)
		)
		(duplicate_pad_numbers_are_jumpers no)
		(fp_line
			(start 0.7874 -0.4064)
			(end -0.7874 -0.4064)
			(stroke
				(width 0.1524)
				(type default)
			)
			(layer "B.SilkS")
		)
		(fp_line
			(start -0.7874 -0.4064)
			(end -0.7874 0.4064)
			(stroke
				(width 0.1524)
				(type default)
			)
			(layer "B.SilkS")
		)
		(fp_line
			(start 0.7874 0.4064)
			(end 0.7874 -0.4064)
			(stroke
				(width 0.1524)
				(type default)
			)
			(layer "B.SilkS")
		)
		(fp_line
			(start -0.7874 0.4064)
			(end 0.7874 0.4064)
			(stroke
				(width 0.1524)
				(type default)
			)
			(layer "B.SilkS")
		)
		(fp_line
			(start 0.67945 -0.305054)
			(end 0.12065 -0.305054)
			(stroke
				(width 0.1)
				(type default)
			)
			(layer "B.Fab")
		)
		(fp_line
			(start 0.12065 -0.305054)
			(end 0.12065 -0.2794)
			(stroke
				(width 0.1)
				(type default)
			)
			(layer "B.Fab")
		)
		(fp_line
			(start -0.12065 -0.3048)
			(end -0.67945 -0.3048)
			(stroke
				(width 0.1)
				(type default)
			)
			(layer "B.Fab")
		)
		(fp_line
			(start -0.67945 -0.3048)
			(end -0.67945 0.3048)
			(stroke
				(width 0.1)
				(type default)
			)
			(layer "B.Fab")
		)
		(fp_line
			(start 0.12065 -0.2794)
			(end -0.12065 -0.2794)
			(stroke
				(width 0.1)
				(type default)
			)
			(layer "B.Fab")
		)
		(fp_line
			(start -0.12065 -0.2794)
			(end -0.12065 -0.3048)
			(stroke
				(width 0.1)
				(type default)
			)
			(layer "B.Fab")
		)
		(fp_line
			(start 0.12065 0.2794)
			(end 0.12065 0.3048)
			(stroke
				(width 0.1)
				(type default)
			)
			(layer "B.Fab")
		)
		(fp_line
			(start -0.120396 0.2794)
			(end 0.12065 0.2794)
			(stroke
				(width 0.1)
				(type default)
			)
			(layer "B.Fab")
		)
		(fp_line
			(start 0.67945 0.3048)
			(end 0.67945 -0.305054)
			(stroke
				(width 0.1)
				(type default)
			)
			(layer "B.Fab")
		)
		(fp_line
			(start 0.12065 0.3048)
			(end 0.67945 0.3048)
			(stroke
				(width 0.1)
				(type default)
			)
			(layer "B.Fab")
		)
		(fp_line
			(start -0.120396 0.3048)
			(end -0.120396 0.2794)
			(stroke
				(width 0.1)
				(type default)
			)
			(layer "B.Fab")
		)
		(fp_line
			(start -0.67945 0.3048)
			(end -0.120396 0.3048)
			(stroke
				(width 0.1)
				(type default)
			)
			(layer "B.Fab")
		)
		(pad "1" smd circle
			(at 0.40005 0 270)
			(size 0 0)
			(layers "B.Cu" "B.Mask" "B.Paste")
			(net "PD_CHH_CPU0_DIMM1_SAA")
		)
		(pad "2" smd circle
			(at -0.40005 0 270)
			(size 0 0)
			(layers "B.Cu" "B.Mask" "B.Paste")
			(net "GND")
		)
	)
	(footprint ""
		(layer "B.Cu")
		(at 381.92583 -190.82131 -90)
		(property "Reference" "R95"
			(at 0 0 90)
			(layer "B.SilkS")
			(hide yes)
			(effects
				(font
					(size 1.27 1.27)
				)
				(justify mirror)
			)
		)
		(property "Value" ""
			(at 0 0 90)
			(layer "B.Fab")
			(effects
				(font
					(size 1.27 1.27)
				)
				(justify mirror)
			)
		)
		(duplicate_pad_numbers_are_jumpers no)
		(fp_line
			(start -0.7874 0.4064)
			(end 0.7874 0.4064)
			(stroke
				(width 0.1524)
				(type default)
			)
			(layer "B.SilkS")
		)
		(fp_line
			(start 0.7874 0.4064)
			(end 0.7874 -0.4064)
			(stroke
				(width 0.1524)
				(type default)
			)
			(layer "B.SilkS")
		)
		(fp_line
			(start -0.7874 -0.4064)
			(end -0.7874 0.4064)
			(stroke
				(width 0.1524)
				(type default)
			)
			(layer "B.SilkS")
		)
		(fp_line
			(start 0.7874 -0.4064)
			(end -0.7874 -0.4064)
			(stroke
				(width 0.1524)
				(type default)
			)
			(layer "B.SilkS")
		)
		(fp_line
			(start -0.67945 0.3048)
			(end -0.120396 0.3048)
			(stroke
				(width 0.1)
				(type default)
			)
			(layer "B.Fab")
		)
		(fp_line
			(start -0.120396 0.3048)
			(end -0.120396 0.2794)
			(stroke
				(width 0.1)
				(type default)
			)
			(layer "B.Fab")
		)
		(fp_line
			(start 0.12065 0.3048)
			(end 0.67945 0.3048)
			(stroke
				(width 0.1)
				(type default)
			)
			(layer "B.Fab")
		)
		(fp_line
			(start 0.67945 0.3048)
			(end 0.67945 -0.305054)
			(stroke
				(width 0.1)
				(type default)
			)
			(layer "B.Fab")
		)
		(fp_line
			(start -0.120396 0.2794)
			(end 0.12065 0.2794)
			(stroke
				(width 0.1)
				(type default)
			)
			(layer "B.Fab")
		)
		(fp_line
			(start 0.12065 0.2794)
			(end 0.12065 0.3048)
			(stroke
				(width 0.1)
				(type default)
			)
			(layer "B.Fab")
		)
		(fp_line
			(start -0.12065 -0.2794)
			(end -0.12065 -0.3048)
			(stroke
				(width 0.1)
				(type default)
			)
			(layer "B.Fab")
		)
		(fp_line
			(start 0.12065 -0.2794)
			(end -0.12065 -0.2794)
			(stroke
				(width 0.1)
				(type default)
			)
			(layer "B.Fab")
		)
		(fp_line
			(start -0.67945 -0.3048)
			(end -0.67945 0.3048)
			(stroke
				(width 0.1)
				(type default)
			)
			(layer "B.Fab")
		)
		(fp_line
			(start -0.12065 -0.3048)
			(end -0.67945 -0.3048)
			(stroke
				(width 0.1)
				(type default)
			)
			(layer "B.Fab")
		)
		(fp_line
			(start 0.12065 -0.305054)
			(end 0.12065 -0.2794)
			(stroke
				(width 0.1)
				(type default)
			)
			(layer "B.Fab")
		)
		(fp_line
			(start 0.67945 -0.305054)
			(end 0.12065 -0.305054)
			(stroke
				(width 0.1)
				(type default)
			)
			(layer "B.Fab")
		)
		(pad "1" smd circle
			(at 0.40005 0 90)
			(size 0 0)
			(layers "B.Cu" "B.Mask" "B.Paste")
			(net "PVNN_TERM_CPU0")
		)
		(pad "2" smd circle
			(at -0.40005 0 90)
			(size 0 0)
			(layers "B.Cu" "B.Mask" "B.Paste")
			(net "PU_CPU0_UPI1_AC_COUPLING")
		)
	)
	(footprint ""
		(layer "B.Cu")
		(at 20.566634 -176.423574 -90)
		(property "Reference" "C1308"
			(at 0 0 90)
			(layer "B.SilkS")
			(hide yes)
			(effects
				(font
					(size 1.27 1.27)
				)
				(justify mirror)
			)
		)
		(property "Value" ""
			(at 0 0 90)
			(layer "B.Fab")
			(effects
				(font
					(size 1.27 1.27)
				)
				(justify mirror)
			)
		)
		(duplicate_pad_numbers_are_jumpers no)
		(fp_line
			(start -0.7874 0.4064)
			(end 0.7874 0.4064)
			(stroke
				(width 0.1524)
				(type default)
			)
			(layer "B.SilkS")
		)
		(fp_line
			(start 0.7874 0.4064)
			(end 0.7874 -0.4064)
			(stroke
				(width 0.1524)
				(type default)
			)
			(layer "B.SilkS")
		)
		(fp_line
			(start -0.7874 -0.4064)
			(end -0.7874 0.4064)
			(stroke
				(width 0.1524)
				(type default)
			)
			(layer "B.SilkS")
		)
		(fp_line
			(start 0.7874 -0.4064)
			(end -0.7874 -0.4064)
			(stroke
				(width 0.1524)
				(type default)
			)
			(layer "B.SilkS")
		)
		(fp_line
			(start -0.67945 0.3048)
			(end -0.120396 0.3048)
			(stroke
				(width 0.1)
				(type default)
			)
			(layer "B.Fab")
		)
		(fp_line
			(start -0.120396 0.3048)
			(end -0.120396 0.2794)
			(stroke
				(width 0.1)
				(type default)
			)
			(layer "B.Fab")
		)
		(fp_line
			(start 0.12065 0.3048)
			(end 0.67945 0.3048)
			(stroke
				(width 0.1)
				(type default)
			)
			(layer "B.Fab")
		)
		(fp_line
			(start 0.67945 0.3048)
			(end 0.67945 -0.305054)
			(stroke
				(width 0.1)
				(type default)
			)
			(layer "B.Fab")
		)
		(fp_line
			(start -0.120396 0.2794)
			(end 0.12065 0.2794)
			(stroke
				(width 0.1)
				(type default)
			)
			(layer "B.Fab")
		)
		(fp_line
			(start 0.12065 0.2794)
			(end 0.12065 0.3048)
			(stroke
				(width 0.1)
				(type default)
			)
			(layer "B.Fab")
		)
		(fp_line
			(start -0.12065 -0.2794)
			(end -0.12065 -0.3048)
			(stroke
				(width 0.1)
				(type default)
			)
			(layer "B.Fab")
		)
		(fp_line
			(start 0.12065 -0.2794)
			(end -0.12065 -0.2794)
			(stroke
				(width 0.1)
				(type default)
			)
			(layer "B.Fab")
		)
		(fp_line
			(start -0.67945 -0.3048)
			(end -0.67945 0.3048)
			(stroke
				(width 0.1)
				(type default)
			)
			(layer "B.Fab")
		)
		(fp_line
			(start -0.12065 -0.3048)
			(end -0.67945 -0.3048)
			(stroke
				(width 0.1)
				(type default)
			)
			(layer "B.Fab")
		)
		(fp_line
			(start 0.12065 -0.305054)
			(end 0.12065 -0.2794)
			(stroke
				(width 0.1)
				(type default)
			)
			(layer "B.Fab")
		)
		(fp_line
			(start 0.67945 -0.305054)
			(end 0.12065 -0.305054)
			(stroke
				(width 0.1)
				(type default)
			)
			(layer "B.Fab")
		)
		(pad "1" smd circle
			(at 0.40005 0 90)
			(size 0 0)
			(layers "B.Cu" "B.Mask" "B.Paste")
			(net "FM_PVNN_MAIN_CPU1_EN")
		)
		(pad "2" smd circle
			(at -0.40005 0 90)
			(size 0 0)
			(layers "B.Cu" "B.Mask" "B.Paste")
			(net "GND")
		)
	)
)
